(kicad_pcb
	(version 20260206)
	(generator "pcbnew")
	(generator_version "10.0")
	(general
		(thickness 1.6)
		(legacy_teardrops no)
	)
	(paper "A4")
	(title_block
		(title "v2-pdb — ms_pdb_v2.brd")
		(comment 1 "Open CloudServer (Microsoft) / footprints 207-210 of 348")
	)
	(layers
		(0 "F.Cu" signal "TOP")
		(4 "In1.Cu" signal "GND")
		(6 "In2.Cu" signal "IN1")
		(8 "In3.Cu" signal "VCC")
		(10 "In4.Cu" signal "VCC1")
		(12 "In5.Cu" signal "IN2")
		(14 "In6.Cu" signal "GND1")
		(2 "B.Cu" signal "BOTTOM")
		(9 "F.Adhes" user "F.Adhesive")
		(11 "B.Adhes" user "B.Adhesive")
		(13 "F.Paste" user "Package Geometry/Pastemask Top")
		(15 "B.Paste" user "Package Geometry/Pastemask Bottom")
		(5 "F.SilkS" user "Ref Des/Silkscreen Top")
		(7 "B.SilkS" user "Ref Des/Silkscreen Bottom")
		(1 "F.Mask" user "Board Geometry/Soldermask Top")
		(3 "B.Mask" user "Board Geometry/Soldermask Bottom")
		(17 "Dwgs.User" user "User.Drawings")
		(19 "Cmts.User" user "User.Comments")
		(21 "Eco1.User" user "User.Eco1")
		(23 "Eco2.User" user "User.Eco2")
		(25 "Edge.Cuts" user "Board Geometry/Outline")
		(27 "Margin" user)
		(31 "F.CrtYd" user "Package Geometry/Place Bound Top")
		(29 "B.CrtYd" user "Package Geometry/Place Bound Bottom")
		(35 "F.Fab" user "Ref Des/Assembly Top")
		(33 "B.Fab" user "Ref Des/Assembly Bottom")
	)
	(footprint ""
		(layer "F.Cu")
		(at 78.000098 -519.049762)
		(property "Reference" "H1"
			(at -5.872734 -7.468108 0)
			(unlocked yes)
			(layer "F.SilkS")
			(effects
				(font
					(size 0.7874 0.5842)
					(thickness 0.1524)
				)
				(justify left)
			)
		)
		(property "Value" ""
			(at 0 0 0)
			(layer "F.Fab")
			(effects
				(font
					(size 1.27 1.27)
				)
			)
		)
		(duplicate_pad_numbers_are_jumpers no)
		(fp_circle
			(center 0 0)
			(end 7.999984 0)
			(stroke
				(width 0.1524)
				(type default)
			)
			(fill no)
			(layer "F.SilkS")
		)
		(fp_circle
			(center 0 0)
			(end 14.7066 0)
			(stroke
				(width 0.1524)
				(type default)
			)
			(fill no)
			(layer "B.SilkS")
		)
		(fp_poly
			(pts
				(arc
					(start 5.0038 0)
					(mid -5.0038 0)
					(end 5.0038 0)
				)
			)
			(stroke
				(width 0)
				(type default)
			)
			(fill no)
			(layer "F.CrtYd")
		)
		(pad "" np_thru_hole circle
			(at 0 0)
			(size 4.0132 4.0132)
			(drill 4.0132)
			(layers "*.Cu" "*.Mask")
			(clearance 0.381)
			(thermal_gap 0.381)
		)
		(pad "2" thru_hole circle
			(at 0 -3.50012)
			(size 0.762 0.762)
			(drill 0.5588)
			(layers "*.Cu" "*.Mask")
			(remove_unused_layers no)
			(net "GND")
			(clearance 0.1524)
			(thermal_gap 0.1524)
		)
		(pad "3" thru_hole circle
			(at -2.500122 -2.500122)
			(size 0.762 0.762)
			(drill 0.5588)
			(layers "*.Cu" "*.Mask")
			(remove_unused_layers no)
			(net "GND")
			(clearance 0.1524)
			(thermal_gap 0.1524)
		)
		(pad "4" thru_hole circle
			(at -3.50012 0)
			(size 0.762 0.762)
			(drill 0.5588)
			(layers "*.Cu" "*.Mask")
			(remove_unused_layers no)
			(net "GND")
			(clearance 0.1524)
			(thermal_gap 0.1524)
		)
		(pad "5" thru_hole circle
			(at -2.500122 2.500122)
			(size 0.762 0.762)
			(drill 0.5588)
			(layers "*.Cu" "*.Mask")
			(remove_unused_layers no)
			(net "GND")
			(clearance 0.1524)
			(thermal_gap 0.1524)
		)
		(pad "6" thru_hole circle
			(at 0 3.50012)
			(size 0.762 0.762)
			(drill 0.5588)
			(layers "*.Cu" "*.Mask")
			(remove_unused_layers no)
			(net "GND")
			(clearance 0.1524)
			(thermal_gap 0.1524)
		)
		(pad "7" thru_hole circle
			(at 2.500122 2.500122)
			(size 0.762 0.762)
			(drill 0.5588)
			(layers "*.Cu" "*.Mask")
			(remove_unused_layers no)
			(net "GND")
			(clearance 0.1524)
			(thermal_gap 0.1524)
		)
		(pad "8" thru_hole circle
			(at 3.50012 0)
			(size 0.762 0.762)
			(drill 0.5588)
			(layers "*.Cu" "*.Mask")
			(remove_unused_layers no)
			(net "GND")
			(clearance 0.1524)
			(thermal_gap 0.1524)
		)
		(pad "9" thru_hole circle
			(at 2.500122 -2.500122)
			(size 0.762 0.762)
			(drill 0.5588)
			(layers "*.Cu" "*.Mask")
			(remove_unused_layers no)
			(net "GND")
			(clearance 0.1524)
			(thermal_gap 0.1524)
		)
		(zone
			(layer "F.Cu")
			(hatch none 0.5)
			(connect_pads
				(clearance 0)
			)
			(min_thickness 0.25)
			(keepout
				(tracks not_allowed)
				(vias allowed)
				(pads allowed)
				(copperpour not_allowed)
				(footprints allowed)
			)
			(placement
				(enabled no)
				(sheetname "")
			)
			(fill
				(thermal_gap 0.5)
				(thermal_bridge_width 0.5)
				(island_removal_mode 0)
			)
			(polygon
				(pts
					(arc
						(start 78.000098 -527.050762)
						(mid 69.999098 -519.049762)
						(end 78.000098 -511.048762)
					)
					(arc
						(start 78.000098 -511.048762)
						(mid 79.435198 -512.483862)
						(end 78.000098 -513.918962)
					)
					(arc
						(start 78.000098 -513.918962)
						(mid 72.869298 -519.049762)
						(end 78.000098 -524.180562)
					)
					(arc
						(start 78.000098 -524.180562)
						(mid 79.435198 -525.615662)
						(end 78.000098 -527.050762)
					)
				)
			)
		)
		(zone
			(layer "F.Cu")
			(hatch none 0.5)
			(connect_pads
				(clearance 0)
			)
			(min_thickness 0.25)
			(keepout
				(tracks not_allowed)
				(vias allowed)
				(pads allowed)
				(copperpour not_allowed)
				(footprints allowed)
			)
			(placement
				(enabled no)
				(sheetname "")
			)
			(fill
				(thermal_gap 0.5)
				(thermal_bridge_width 0.5)
				(island_removal_mode 0)
			)
			(polygon
				(pts
					(arc
						(start 78.000098 -527.050762)
						(mid 86.001098 -519.049762)
						(end 78.000098 -511.048762)
					)
					(arc
						(start 78.000098 -511.048762)
						(mid 76.564998 -512.483862)
						(end 78.000098 -513.918962)
					)
					(arc
						(start 78.000098 -513.918962)
						(mid 83.130898 -519.049762)
						(end 78.000098 -524.180562)
					)
					(arc
						(start 78.000098 -524.180562)
						(mid 76.564998 -525.615662)
						(end 78.000098 -527.050762)
					)
				)
			)
		)
		(zone
			(layers "F.Cu" "B.Cu" "In1.Cu" "In2.Cu" "In3.Cu" "In4.Cu" "In5.Cu" "In6.Cu")
			(hatch none 0.5)
			(connect_pads
				(clearance 0)
			)
			(min_thickness 0.25)
			(keepout
				(tracks not_allowed)
				(vias allowed)
				(pads allowed)
				(copperpour not_allowed)
				(footprints allowed)
			)
			(placement
				(enabled no)
				(sheetname "")
			)
			(fill
				(thermal_gap 0.5)
				(thermal_bridge_width 0.5)
				(island_removal_mode 0)
			)
			(polygon
				(pts
					(arc
						(start 80.512158 -519.049762)
						(mid 75.488038 -519.049762)
						(end 80.512158 -519.049762)
					)
				)
			)
		)
	)
	(footprint ""
		(layer "F.Cu")
		(at 13.964666 -17.907 -90)
		(property "Reference" "J19"
			(at -4.500372 7.138416 0)
			(unlocked yes)
			(layer "F.SilkS")
			(effects
				(font
					(size 0.7874 0.5842)
					(thickness 0.1524)
				)
				(justify left)
			)
		)
		(property "Value" ""
			(at 0 0 270)
			(layer "F.Fab")
			(effects
				(font
					(size 1.27 1.27)
				)
			)
		)
		(duplicate_pad_numbers_are_jumpers no)
		(fp_line
			(start -3.370072 12.830048)
			(end -3.370072 -3.81)
			(stroke
				(width 0.1524)
				(type default)
			)
			(layer "F.SilkS")
		)
		(fp_line
			(start 12.260072 12.830048)
			(end -3.370072 12.830048)
			(stroke
				(width 0.1524)
				(type default)
			)
			(layer "F.SilkS")
		)
		(fp_line
			(start -3.370072 -3.81)
			(end 12.260072 -3.81)
			(stroke
				(width 0.1524)
				(type default)
			)
			(layer "F.SilkS")
		)
		(fp_line
			(start 12.260072 -3.81)
			(end 12.260072 12.830048)
			(stroke
				(width 0.1524)
				(type default)
			)
			(layer "F.SilkS")
		)
		(fp_poly
			(pts
				(xy -3.631946 2.173224) (xy -3.856736 3.752596) (xy -5.03047 2.940812)
			)
			(stroke
				(width 0)
				(type default)
			)
			(fill yes)
			(layer "F.SilkS")
		)
		(fp_poly
			(pts
				(xy -0.762 0.762) (xy 8.382 0.762) (xy 8.382 -1.8034) (xy 9.652 -1.8034) (xy 9.652 -3.302) (xy 0.508 -3.302)
				(xy 0.508 -0.762) (xy -0.762 -0.762)
			)
			(stroke
				(width 0)
				(type default)
			)
			(fill no)
			(layer "B.CrtYd")
		)
		(fp_poly
			(pts
				(arc
					(start -1.27 4.4196)
					(mid -1.27 8.2804)
					(end -1.27 4.4196)
				)
			)
			(stroke
				(width 0)
				(type default)
			)
			(fill no)
			(layer "B.CrtYd")
		)
		(fp_poly
			(pts
				(arc
					(start 10.16 4.4196)
					(mid 10.16 8.2804)
					(end 10.16 4.4196)
				)
			)
			(stroke
				(width 0)
				(type default)
			)
			(fill no)
			(layer "B.CrtYd")
		)
		(fp_poly
			(pts
				(xy -3.370072 12.830048) (xy 12.260072 12.830048) (xy 12.260072 -3.81) (xy -3.370072 -3.81)
			)
			(stroke
				(width 0)
				(type default)
			)
			(fill no)
			(layer "F.CrtYd")
		)
		(fp_line
			(start -3.370072 12.830048)
			(end -3.370072 -3.81)
			(stroke
				(width 0.1)
				(type default)
			)
			(layer "F.Fab")
		)
		(fp_line
			(start 12.260072 12.830048)
			(end -3.370072 12.830048)
			(stroke
				(width 0.1)
				(type default)
			)
			(layer "F.Fab")
		)
		(fp_line
			(start -3.370072 -3.81)
			(end 12.260072 -3.81)
			(stroke
				(width 0.1)
				(type default)
			)
			(layer "F.Fab")
		)
		(fp_line
			(start 12.260072 -3.81)
			(end 12.260072 12.830048)
			(stroke
				(width 0.1)
				(type default)
			)
			(layer "F.Fab")
		)
		(fp_poly
			(pts
				(xy -3.576828 0) (xy -5.0038 0.713486) (xy -5.0038 -0.713486)
			)
			(stroke
				(width 0)
				(type default)
			)
			(fill yes)
			(layer "F.Fab")
		)
		(fp_text user "1"
			(at -3.98399 1.897126 0)
			(unlocked yes)
			(layer "F.SilkS")
			(effects
				(font
					(size 0.7874 0.5842)
					(thickness 0.1524)
				)
			)
		)
		(fp_text user "7"
			(at 12.980924 0.338836 0)
			(unlocked yes)
			(layer "F.SilkS")
			(effects
				(font
					(size 0.7874 0.5842)
					(thickness 0.1524)
				)
			)
		)
		(fp_text user "8"
			(at 12.95019 -2.418334 0)
			(unlocked yes)
			(layer "F.SilkS")
			(effects
				(font
					(size 0.7874 0.5842)
					(thickness 0.1524)
				)
			)
		)
		(fp_text user "2"
			(at -2.72923 -4.624832 0)
			(unlocked yes)
			(layer "F.SilkS")
			(effects
				(font
					(size 0.7874 0.5842)
					(thickness 0.1524)
				)
			)
		)
		(fp_text user "7"
			(at 9.215628 0.267208 0)
			(unlocked yes)
			(layer "B.SilkS")
			(effects
				(font
					(size 0.7874 0.5842)
					(thickness 0.1524)
				)
				(justify mirror)
			)
		)
		(fp_text user "1"
			(at -1.522476 0.234442 0)
			(unlocked yes)
			(layer "B.SilkS")
			(effects
				(font
					(size 0.7874 0.5842)
					(thickness 0.1524)
				)
				(justify mirror)
			)
		)
		(fp_text user "8"
			(at 10.566146 -2.883662 0)
			(unlocked yes)
			(layer "B.SilkS")
			(effects
				(font
					(size 0.7874 0.5842)
					(thickness 0.1524)
				)
				(justify mirror)
			)
		)
		(fp_text user "2"
			(at -0.42418 -2.948178 0)
			(unlocked yes)
			(layer "B.SilkS")
			(effects
				(font
					(size 0.7874 0.5842)
					(thickness 0.1524)
				)
				(justify mirror)
			)
		)
		(fp_text user "7"
			(at 8.8138 0.238252 270)
			(unlocked yes)
			(layer "B.Fab")
			(effects
				(font
					(size 0.7874 0.5842)
					(thickness 0.000001)
				)
				(justify mirror)
			)
		)
		(fp_text user "1"
			(at -1.2954 0.085852 270)
			(unlocked yes)
			(layer "B.Fab")
			(effects
				(font
					(size 0.7874 0.5842)
					(thickness 0.000001)
				)
				(justify mirror)
			)
		)
		(fp_text user "8"
			(at 10.0838 -2.403348 270)
			(unlocked yes)
			(layer "B.Fab")
			(effects
				(font
					(size 0.7874 0.5842)
					(thickness 0.000001)
				)
				(justify mirror)
			)
		)
		(fp_text user "2"
			(at 0 -2.581148 270)
			(unlocked yes)
			(layer "B.Fab")
			(effects
				(font
					(size 0.7874 0.5842)
					(thickness 0.000001)
				)
				(justify mirror)
			)
		)
		(fp_text user "7"
			(at 12.7762 -0.091948 270)
			(unlocked yes)
			(layer "F.Fab")
			(effects
				(font
					(size 0.7874 0.5842)
					(thickness 0.000001)
				)
			)
		)
		(fp_text user "1"
			(at -3.9116 -0.930148 270)
			(unlocked yes)
			(layer "F.Fab")
			(effects
				(font
					(size 0.7874 0.5842)
					(thickness 0.000001)
				)
			)
		)
		(fp_text user "2"
			(at -3.9624 -2.428748 270)
			(unlocked yes)
			(layer "F.Fab")
			(effects
				(font
					(size 0.7874 0.5842)
					(thickness 0.000001)
				)
			)
		)
		(fp_text user "8"
			(at 12.7762 -2.555748 270)
			(unlocked yes)
			(layer "F.Fab")
			(effects
				(font
					(size 0.7874 0.5842)
					(thickness 0.000001)
				)
			)
		)
		(pad "" np_thru_hole circle
			(at -1.27 6.35 270)
			(size 3.3528 3.3528)
			(drill 3.3528)
			(layers "*.Cu" "*.Mask")
			(clearance 0.381)
			(thermal_gap 0.381)
		)
		(pad "" np_thru_hole circle
			(at 10.16 6.35 270)
			(size 3.3528 3.3528)
			(drill 3.3528)
			(layers "*.Cu" "*.Mask")
			(clearance 0.381)
			(thermal_gap 0.381)
		)
		(pad "1" thru_hole rect
			(at 0 0 270)
			(size 1.397 1.397)
			(drill 0.9906)
			(layers "*.Cu" "*.Mask")
			(remove_unused_layers no)
			(net "UART_RTS_P1_L_N")
			(clearance 0.0508)
			(thermal_gap 0.0508)
			(padstack
				(mode front_inner_back)
				(layer "Inner"
					(shape circle)
					(size 1.397 1.397)
					(clearance 0.0508)
				)
				(layer "B.Cu"
					(shape rect)
					(size 1.397 1.397)
					(clearance 0.0508)
				)
			)
		)
		(pad "2" thru_hole circle
			(at 1.27 -2.54 270)
			(size 1.397 1.397)
			(drill 0.9906)
			(layers "*.Cu" "*.Mask")
			(remove_unused_layers no)
			(net "UART_DSR_P1_L_N")
			(clearance 0.0508)
			(thermal_gap 0.0508)
		)
		(pad "3" thru_hole circle
			(at 2.54 0 270)
			(size 1.397 1.397)
			(drill 0.9906)
			(layers "*.Cu" "*.Mask")
			(remove_unused_layers no)
			(net "UART_RX_P1_L")
			(clearance 0.0508)
			(thermal_gap 0.0508)
		)
		(pad "4" thru_hole circle
			(at 3.81 -2.54 270)
			(size 1.397 1.397)
			(drill 0.9906)
			(layers "*.Cu" "*.Mask")
			(remove_unused_layers no)
			(net "GND")
			(clearance 0.0508)
			(thermal_gap 0.0508)
		)
		(pad "5" thru_hole circle
			(at 5.08 0 270)
			(size 1.397 1.397)
			(drill 0.9906)
			(layers "*.Cu" "*.Mask")
			(remove_unused_layers no)
			(net "GND")
			(clearance 0.0508)
			(thermal_gap 0.0508)
		)
		(pad "6" thru_hole circle
			(at 6.35 -2.54 270)
			(size 1.397 1.397)
			(drill 0.9906)
			(layers "*.Cu" "*.Mask")
			(remove_unused_layers no)
			(net "UART_TX_P1_L")
			(clearance 0.0508)
			(thermal_gap 0.0508)
		)
		(pad "7" thru_hole circle
			(at 7.62 0 270)
			(size 1.397 1.397)
			(drill 0.9906)
			(layers "*.Cu" "*.Mask")
			(remove_unused_layers no)
			(net "UART_DTR_P1_L_N")
			(clearance 0.0508)
			(thermal_gap 0.0508)
		)
		(pad "8" thru_hole circle
			(at 8.89 -2.54 270)
			(size 1.397 1.397)
			(drill 0.9906)
			(layers "*.Cu" "*.Mask")
			(remove_unused_layers no)
			(net "UART_CTS_P1_L_N")
			(clearance 0.0508)
			(thermal_gap 0.0508)
		)
		(zone
			(layers "F.Cu" "B.Cu" "In1.Cu" "In2.Cu" "In3.Cu" "In4.Cu" "In5.Cu" "In6.Cu")
			(hatch none 0.5)
			(connect_pads
				(clearance 0)
			)
			(min_thickness 0.25)
			(keepout
				(tracks not_allowed)
				(vias allowed)
				(pads allowed)
				(copperpour not_allowed)
				(footprints allowed)
			)
			(placement
				(enabled no)
				(sheetname "")
			)
			(fill
				(thermal_gap 0.5)
				(thermal_bridge_width 0.5)
				(island_removal_mode 0)
			)
			(polygon
				(pts
					(arc
						(start 9.697466 -19.177)
						(mid 5.531866 -19.177)
						(end 9.697466 -19.177)
					)
				)
			)
		)
		(zone
			(layers "F.Cu" "B.Cu" "In1.Cu" "In2.Cu" "In3.Cu" "In4.Cu" "In5.Cu" "In6.Cu")
			(hatch none 0.5)
			(connect_pads
				(clearance 0)
			)
			(min_thickness 0.25)
			(keepout
				(tracks not_allowed)
				(vias allowed)
				(pads allowed)
				(copperpour not_allowed)
				(footprints allowed)
			)
			(placement
				(enabled no)
				(sheetname "")
			)
			(fill
				(thermal_gap 0.5)
				(thermal_bridge_width 0.5)
				(island_removal_mode 0)
			)
			(polygon
				(pts
					(arc
						(start 9.697466 -7.747)
						(mid 5.531866 -7.747)
						(end 9.697466 -7.747)
					)
				)
			)
		)
	)
	(footprint ""
		(layer "F.Cu")
		(at 78.062074 -387.197854 180)
		(property "Reference" "R127"
			(at 0.888492 1.176274 0)
			(unlocked yes)
			(layer "F.SilkS")
			(effects
				(font
					(size 0.7874 0.5842)
					(thickness 0.1524)
				)
				(justify left)
			)
		)
		(property "Value" ""
			(at 0 0 180)
			(layer "F.Fab")
			(effects
				(font
					(size 1.27 1.27)
				)
			)
		)
		(duplicate_pad_numbers_are_jumpers no)
		(fp_line
			(start 0.7874 0.4064)
			(end -0.7874 0.4064)
			(stroke
				(width 0.1524)
				(type default)
			)
			(layer "F.SilkS")
		)
		(fp_line
			(start 0.7874 -0.4064)
			(end 0.7874 0.4064)
			(stroke
				(width 0.1524)
				(type default)
			)
			(layer "F.SilkS")
		)
		(fp_line
			(start -0.7874 0.4064)
			(end -0.7874 -0.4064)
			(stroke
				(width 0.1524)
				(type default)
			)
			(layer "F.SilkS")
		)
		(fp_line
			(start -0.7874 -0.4064)
			(end 0.7874 -0.4064)
			(stroke
				(width 0.1524)
				(type default)
			)
			(layer "F.SilkS")
		)
		(fp_poly
			(pts
				(xy -0.508 0.2794) (xy -0.508 0.2286) (xy -0.635 0.2286) (xy -0.635 -0.254) (xy -0.5334 -0.254)
				(xy -0.5334 -0.2794) (xy 0.5334 -0.2794) (xy 0.5334 -0.254) (xy 0.635 -0.254) (xy 0.635 0.254) (xy 0.5334 0.254)
				(xy 0.5334 0.2794)
			)
			(stroke
				(width 0)
				(type default)
			)
			(fill no)
			(layer "F.CrtYd")
		)
		(pad "1" smd rect
			(at 0.40005 0 180)
			(size 0.4572 0.508)
			(layers "F.Cu" "F.Mask" "F.Paste")
			(net "PSU5_REMOTE_R2_P")
		)
		(pad "2" smd rect
			(at -0.40005 0 180)
			(size 0.4572 0.508)
			(layers "F.Cu" "F.Mask" "F.Paste")
			(net "P12V")
		)
	)
	(footprint ""
		(layer "F.Cu")
		(at 13.36929 -320.828162 180)
		(property "Reference" "R144"
			(at -1.74244 -0.214122 0)
			(unlocked yes)
			(layer "F.SilkS")
			(effects
				(font
					(size 0.7874 0.5842)
					(thickness 0.1524)
				)
				(justify left)
			)
		)
		(property "Value" ""
			(at 0 0 180)
			(layer "F.Fab")
			(effects
				(font
					(size 1.27 1.27)
				)
			)
		)
		(duplicate_pad_numbers_are_jumpers no)
		(fp_line
			(start 0.7874 0.4064)
			(end -0.7874 0.4064)
			(stroke
				(width 0.1524)
				(type default)
			)
			(layer "F.SilkS")
		)
		(fp_line
			(start 0.7874 -0.4064)
			(end 0.7874 0.4064)
			(stroke
				(width 0.1524)
				(type default)
			)
			(layer "F.SilkS")
		)
		(fp_line
			(start -0.7874 0.4064)
			(end -0.7874 -0.4064)
			(stroke
				(width 0.1524)
				(type default)
			)
			(layer "F.SilkS")
		)
		(fp_line
			(start -0.7874 -0.4064)
			(end 0.7874 -0.4064)
			(stroke
				(width 0.1524)
				(type default)
			)
			(layer "F.SilkS")
		)
		(fp_poly
			(pts
				(xy -0.508 0.2794) (xy -0.508 0.2286) (xy -0.635 0.2286) (xy -0.635 -0.254) (xy -0.5334 -0.254)
				(xy -0.5334 -0.2794) (xy 0.5334 -0.2794) (xy 0.5334 -0.254) (xy 0.635 -0.254) (xy 0.635 0.254) (xy 0.5334 0.254)
				(xy 0.5334 0.2794)
			)
			(stroke
				(width 0)
				(type default)
			)
			(fill no)
			(layer "F.CrtYd")
		)
		(pad "1" smd rect
			(at 0.40005 0 180)
			(size 0.4572 0.508)
			(layers "F.Cu" "F.Mask" "F.Paste")
			(net "FAN3_TACH")
		)
		(pad "2" smd rect
			(at -0.40005 0 180)
			(size 0.4572 0.508)
			(layers "F.Cu" "F.Mask" "F.Paste")
			(net "P12V")
		)
	)
)
